FILE_TYPE = MACRO_DRAWING;
SET COLOR_WIRE YELLOW;
SET COLOR_PROP MONO;
SET COLOR_DOT WHITE;
SET COLOR_ARC YELLOW;
SET COLOR_BODY GREEN;
SET COLOR_NOTE MONO;
SET PROP_DISPLAY VALUE;
SET PAGE_NUMBER P248;
FORCEADD INTEL_CORP_BPAGE..1
(0 0);
FORCEPROP 1 LAST CUSTOM_TXT_CDS <CURRENT_DESIGN_SHEET> OF <TOTAL_DESIGN_SHEETS>
J 0
(-500 25);
PAINT GREEN (-500 25);
FORCEPROP 1 LAST CUSTOM_TXT_CDS <CON_LAST_MODIFIED>
J 0
(-1925 350);
PAINT GREEN (-1925 350);
FORCEPROP 2 LAST CUSTOM_TXT_CDS <XR_PAGE_TITLE>
J 0
(-7890 5250);
DISPLAY 0.638298 (-7890 5250);
PAINT PINK (-7890 5250);
DISPLAY INVISIBLE (-7890 5250);
FORCEPROP 1 LAST SCH_DEPT UNKNOWN
J 1
(-4450 100);
DISPLAY 1.255319 (-4450 100);
PAINT ORANGE (-4450 100);
FORCEPROP 1 LAST SCH_NUMBER 000000-000
J 0
(-1300 150);
DISPLAY 1.702128 (-1300 150);
PAINT GREEN (-1300 150);
FORCEPROP 1 LAST SCH_REV 0.1
J 0
(-250 150);
DISPLAY 1.170213 (-250 150);
PAINT GREEN (-250 150);
FORCEPROP 1 LAST SCH_ADDRESS3 Santa Clara, CA 95052-8119
J 0
(-3975 25);
DISPLAY 0.872340 (-3975 25);
PAINT GREEN (-3975 25);
FORCEPROP 1 LAST SCH_ADDRESS2 P.O. BOX 58119
J 0
(-3975 75);
DISPLAY 0.872340 (-3975 75);
PAINT GREEN (-3975 75);
FORCEPROP 1 LAST SCH_ADDRESS1 2200 Mission College Blvd.
J 0
(-3975 125);
DISPLAY 0.872340 (-3975 125);
PAINT GREEN (-3975 125);
FORCEPROP 1 LAST SCH_TITLE Blank
J 0
(-7950 50);
DISPLAY 2.468085 (-7950 50);
PAINT ORANGE (-7950 50);
FORCEPROP 2 LAST CDS_LIB mstr_symbols
J 0
(0 0);
PAINT MONO (0 0);
DISPLAY INVISIBLE (0 0);
FORCEPROP 1 LAST COMMENT_BODY TRUE
J 0
(12 12);
DISPLAY 0.468085 (12 12);
PAINT GREEN (12 12);
DISPLAY INVISIBLE (12 12);
FORCEPROP 2 LAST PAGE_BORDER TRUE
J 0
(-7890 5250);
DISPLAY 0.638298 (-7890 5250);
PAINT PINK (-7890 5250);
DISPLAY INVISIBLE (-7890 5250);
FORCEPROP 1 LAST CDS_CON_LAST_MODIFIED Tue Dec 01 11:49:13 2015
J 0
(-1425 325);
PAINT ORANGE (-1425 325);
DISPLAY INVISIBLE (-1425 325);
FORCEPROP 2 LAST CDS_XR_PAGE_TITLE CR-248 : @BASEBOARD_FAB2_LIB.BASEBOARD_FAB2(SCH_1):PAGE248
J 0
(-7890 5250);
DISPLAY 0.638298 (-7890 5250);
PAINT PINK (-7890 5250);
DISPLAY INVISIBLE (-7890 5250);
QUIT
